# T6G (Grand Teton) — schematic netlist excerpt (pin names and nets, part order shuffled) for the footprints in the layout excerpt that follows; sources: Cadence DE-HDL packaged netlist, KiCad conversion of 04192023_DAF0TMB3IC0_F0TG_MB_C_brd_V02_OCP.brd

R6221  Q_RES  10K 1% CHIP  pkg 0402LF  page 176 : A = USB_CPU0_ADD_A2 ; B = GND
C110  Q_CAP  22UF 4V 20% X6S  pkg C0402  page 334 : A = P1V8_CPU1_RT_1D ; B = GND

(kicad_pcb
	(version 20260206)
	(generator "pcbnew")
	(generator_version "10.0")
	(general
		(thickness 1.6)
		(legacy_teardrops no)
	)
	(paper "A4")
	(title_block
		(title "04192023_DAF0TMB3IC0_F0TG_MB_C_brd_V02_OCP.brd")
		(comment 1 "Grand Teton / footprints 2659-2660 of 8354")
	)
	(layers
		(0 "F.Cu" signal "TOP")
		(4 "In1.Cu" signal "GND")
		(6 "In2.Cu" signal "IN1")
		(8 "In3.Cu" signal "GND1")
		(10 "In4.Cu" signal "IN2")
		(12 "In5.Cu" signal "GND2")
		(14 "In6.Cu" signal "IN3")
		(16 "In7.Cu" signal "GND3")
		(18 "In8.Cu" signal "VCC")
		(20 "In9.Cu" signal "VCC1")
		(22 "In10.Cu" signal "GND4")
		(24 "In11.Cu" signal "IN4")
		(26 "In12.Cu" signal "GND5")
		(28 "In13.Cu" signal "IN5")
		(30 "In14.Cu" signal "GND6")
		(32 "In15.Cu" signal "IN6")
		(34 "In16.Cu" signal "GND7")
		(2 "B.Cu" signal "BOTTOM")
		(9 "F.Adhes" user "F.Adhesive")
		(11 "B.Adhes" user "B.Adhesive")
		(13 "F.Paste" user "Package Geometry/Pastemask Top")
		(15 "B.Paste" user "Package Geometry/Pastemask Bottom")
		(5 "F.SilkS" user "Ref Des/Silkscreen Top")
		(7 "B.SilkS" user "Ref Des/Silkscreen Bottom")
		(1 "F.Mask" user "Board Geometry/Soldermask Top")
		(3 "B.Mask" user "Board Geometry/Soldermask Bottom")
		(17 "Dwgs.User" user "User.Drawings")
		(19 "Cmts.User" user "User.Comments")
		(21 "Eco1.User" user "User.Eco1")
		(23 "Eco2.User" user "User.Eco2")
		(25 "Edge.Cuts" user "Board Geometry/Outline")
		(27 "Margin" user)
		(31 "F.CrtYd" user "Package Geometry/Place Bound Top")
		(29 "B.CrtYd" user "Package Geometry/Place Bound Bottom")
		(35 "F.Fab" user "Ref Des/Assembly Top")
		(33 "B.Fab" user "Ref Des/Assembly Bottom")
	)
	(footprint ""
		(layer "F.Cu")
		(at 103.520494 -386.44068 90)
		(property "Reference" "C110"
			(at 0 0 90)
			(layer "F.SilkS")
			(hide yes)
			(effects
				(font
					(size 1.27 1.27)
				)
			)
		)
		(property "Value" ""
			(at 0 0 90)
			(layer "F.Fab")
			(effects
				(font
					(size 1.27 1.27)
				)
			)
		)
		(duplicate_pad_numbers_are_jumpers no)
		(fp_line
			(start 0.7874 -0.4064)
			(end 0.7874 0.4064)
			(stroke
				(width 0.1524)
				(type default)
			)
			(layer "F.SilkS")
		)
		(fp_line
			(start -0.7874 -0.4064)
			(end 0.7874 -0.4064)
			(stroke
				(width 0.1524)
				(type default)
			)
			(layer "F.SilkS")
		)
		(fp_line
			(start 0.7874 0.4064)
			(end -0.7874 0.4064)
			(stroke
				(width 0.1524)
				(type default)
			)
			(layer "F.SilkS")
		)
		(fp_line
			(start -0.7874 0.4064)
			(end -0.7874 -0.4064)
			(stroke
				(width 0.1524)
				(type default)
			)
			(layer "F.SilkS")
		)
		(fp_line
			(start -0.12065 -0.305054)
			(end -0.12065 -0.2794)
			(stroke
				(width 0.1)
				(type default)
			)
			(layer "F.Fab")
		)
		(fp_line
			(start -0.67945 -0.305054)
			(end -0.12065 -0.305054)
			(stroke
				(width 0.1)
				(type default)
			)
			(layer "F.Fab")
		)
		(fp_line
			(start 0.67945 -0.3048)
			(end 0.67945 0.3048)
			(stroke
				(width 0.1)
				(type default)
			)
			(layer "F.Fab")
		)
		(fp_line
			(start 0.12065 -0.3048)
			(end 0.67945 -0.3048)
			(stroke
				(width 0.1)
				(type default)
			)
			(layer "F.Fab")
		)
		(fp_line
			(start 0.12065 -0.2794)
			(end 0.12065 -0.3048)
			(stroke
				(width 0.1)
				(type default)
			)
			(layer "F.Fab")
		)
		(fp_line
			(start -0.12065 -0.2794)
			(end 0.12065 -0.2794)
			(stroke
				(width 0.1)
				(type default)
			)
			(layer "F.Fab")
		)
		(fp_line
			(start 0.120396 0.2794)
			(end -0.12065 0.2794)
			(stroke
				(width 0.1)
				(type default)
			)
			(layer "F.Fab")
		)
		(fp_line
			(start -0.12065 0.2794)
			(end -0.12065 0.3048)
			(stroke
				(width 0.1)
				(type default)
			)
			(layer "F.Fab")
		)
		(fp_line
			(start 0.67945 0.3048)
			(end 0.120396 0.3048)
			(stroke
				(width 0.1)
				(type default)
			)
			(layer "F.Fab")
		)
		(fp_line
			(start 0.120396 0.3048)
			(end 0.120396 0.2794)
			(stroke
				(width 0.1)
				(type default)
			)
			(layer "F.Fab")
		)
		(fp_line
			(start -0.12065 0.3048)
			(end -0.67945 0.3048)
			(stroke
				(width 0.1)
				(type default)
			)
			(layer "F.Fab")
		)
		(fp_line
			(start -0.67945 0.3048)
			(end -0.67945 -0.305054)
			(stroke
				(width 0.1)
				(type default)
			)
			(layer "F.Fab")
		)
		(pad "1" smd circle
			(at -0.40005 0 90)
			(size 0 0)
			(layers "F.Cu" "F.Mask" "F.Paste")
			(net "P1V8_CPU1_RT_1D")
		)
		(pad "2" smd circle
			(at 0.40005 0 90)
			(size 0 0)
			(layers "F.Cu" "F.Mask" "F.Paste")
			(net "GND")
		)
	)
	(footprint ""
		(layer "F.Cu")
		(at 105.84561 -64.55791 180)
		(property "Reference" "R6221"
			(at 0 0 180)
			(layer "F.SilkS")
			(hide yes)
			(effects
				(font
					(size 1.27 1.27)
				)
			)
		)
		(property "Value" ""
			(at 0 0 180)
			(layer "F.Fab")
			(effects
				(font
					(size 1.27 1.27)
				)
			)
		)
		(duplicate_pad_numbers_are_jumpers no)
		(fp_line
			(start 0.7874 0.4064)
			(end -0.7874 0.4064)
			(stroke
				(width 0.1524)
				(type default)
			)
			(layer "F.SilkS")
		)
		(fp_line
			(start 0.7874 -0.4064)
			(end 0.7874 0.4064)
			(stroke
				(width 0.1524)
				(type default)
			)
			(layer "F.SilkS")
		)
		(fp_line
			(start -0.7874 0.4064)
			(end -0.7874 -0.4064)
			(stroke
				(width 0.1524)
				(type default)
			)
			(layer "F.SilkS")
		)
		(fp_line
			(start -0.7874 -0.4064)
			(end 0.7874 -0.4064)
			(stroke
				(width 0.1524)
				(type default)
			)
			(layer "F.SilkS")
		)
		(fp_line
			(start 0.67945 0.3048)
			(end 0.120396 0.3048)
			(stroke
				(width 0.1)
				(type default)
			)
			(layer "F.Fab")
		)
		(fp_line
			(start 0.67945 -0.3048)
			(end 0.67945 0.3048)
			(stroke
				(width 0.1)
				(type default)
			)
			(layer "F.Fab")
		)
		(fp_line
			(start 0.12065 -0.2794)
			(end 0.12065 -0.3048)
			(stroke
				(width 0.1)
				(type default)
			)
			(layer "F.Fab")
		)
		(fp_line
			(start 0.12065 -0.3048)
			(end 0.67945 -0.3048)
			(stroke
				(width 0.1)
				(type default)
			)
			(layer "F.Fab")
		)
		(fp_line
			(start 0.120396 0.3048)
			(end 0.120396 0.2794)
			(stroke
				(width 0.1)
				(type default)
			)
			(layer "F.Fab")
		)
		(fp_line
			(start 0.120396 0.2794)
			(end -0.12065 0.2794)
			(stroke
				(width 0.1)
				(type default)
			)
			(layer "F.Fab")
		)
		(fp_line
			(start -0.12065 0.3048)
			(end -0.67945 0.3048)
			(stroke
				(width 0.1)
				(type default)
			)
			(layer "F.Fab")
		)
		(fp_line
			(start -0.12065 0.2794)
			(end -0.12065 0.3048)
			(stroke
				(width 0.1)
				(type default)
			)
			(layer "F.Fab")
		)
		(fp_line
			(start -0.12065 -0.2794)
			(end 0.12065 -0.2794)
			(stroke
				(width 0.1)
				(type default)
			)
			(layer "F.Fab")
		)
		(fp_line
			(start -0.12065 -0.305054)
			(end -0.12065 -0.2794)
			(stroke
				(width 0.1)
				(type default)
			)
			(layer "F.Fab")
		)
		(fp_line
			(start -0.67945 0.3048)
			(end -0.67945 -0.305054)
			(stroke
				(width 0.1)
				(type default)
			)
			(layer "F.Fab")
		)
		(fp_line
			(start -0.67945 -0.305054)
			(end -0.12065 -0.305054)
			(stroke
				(width 0.1)
				(type default)
			)
			(layer "F.Fab")
		)
		(pad "1" smd circle
			(at -0.40005 0 180)
			(size 0 0)
			(layers "F.Cu" "F.Mask" "F.Paste")
			(net "USB_CPU0_ADD_A2")
		)
		(pad "2" smd circle
			(at 0.40005 0 180)
			(size 0 0)
			(layers "F.Cu" "F.Mask" "F.Paste")
			(net "GND")
		)
	)
)
